# S9S_MB_2U (Grand Teton) — schematic netlist excerpt (pin names and nets, part order shuffled) for the footprints in the layout excerpt that follows; sources: Cadence DE-HDL packaged netlist, KiCad conversion of 03242023_DA0F0TMBIJ0_F0T_Motherboard_J_brd_V01_OCP.brd

PR357  Q_RES  28K 1% EMPTY  pkg 0402LF  page 278 : A = PVCCD_HV_CPU0_VREF ; B = PVCCD_HV_CPU0_ADDR
R1011  Q_RES  0 5% CHIP  pkg 0402LF  page 209 : A = CLK_25M_CK440_ISCLK_REF_DN ; B = CLK_25M_PCH_REF_NS_DN

(kicad_pcb
	(version 20260206)
	(generator "pcbnew")
	(generator_version "10.0")
	(general
		(thickness 1.6)
		(legacy_teardrops no)
	)
	(paper "A4")
	(title_block
		(title "03242023_DA0F0TMBIJ0_F0T_Motherboard_J_brd_V01_OCP.brd")
		(comment 1 "Grand Teton / footprints 2695-2696 of 6105")
	)
	(layers
		(0 "F.Cu" signal "TOP")
		(4 "In1.Cu" signal "GND")
		(6 "In2.Cu" signal "IN1")
		(8 "In3.Cu" signal "GND1")
		(10 "In4.Cu" signal "IN2")
		(12 "In5.Cu" signal "GND2")
		(14 "In6.Cu" signal "IN3")
		(16 "In7.Cu" signal "GND3")
		(18 "In8.Cu" signal "VCC")
		(20 "In9.Cu" signal "VCC1")
		(22 "In10.Cu" signal "GND4")
		(24 "In11.Cu" signal "IN4")
		(26 "In12.Cu" signal "GND5")
		(28 "In13.Cu" signal "IN5")
		(30 "In14.Cu" signal "GND6")
		(32 "In15.Cu" signal "IN6")
		(34 "In16.Cu" signal "GND7")
		(2 "B.Cu" signal "BOTTOM")
		(9 "F.Adhes" user "F.Adhesive")
		(11 "B.Adhes" user "B.Adhesive")
		(13 "F.Paste" user "Package Geometry/Pastemask Top")
		(15 "B.Paste" user "Package Geometry/Pastemask Bottom")
		(5 "F.SilkS" user "Ref Des/Silkscreen Top")
		(7 "B.SilkS" user "Ref Des/Silkscreen Bottom")
		(1 "F.Mask" user "Board Geometry/Soldermask Top")
		(3 "B.Mask" user "Board Geometry/Soldermask Bottom")
		(17 "Dwgs.User" user "User.Drawings")
		(19 "Cmts.User" user "User.Comments")
		(21 "Eco1.User" user "User.Eco1")
		(23 "Eco2.User" user "User.Eco2")
		(25 "Edge.Cuts" user "Board Geometry/Outline")
		(27 "Margin" user)
		(31 "F.CrtYd" user "Package Geometry/Place Bound Top")
		(29 "B.CrtYd" user "Package Geometry/Place Bound Bottom")
		(35 "F.Fab" user "Ref Des/Assembly Top")
		(33 "B.Fab" user "Ref Des/Assembly Bottom")
	)
	(footprint ""
		(layer "F.Cu")
		(at 251.74956 -108.192824 90)
		(property "Reference" "R1011"
			(at 0 0 90)
			(layer "F.SilkS")
			(hide yes)
			(effects
				(font
					(size 1.27 1.27)
				)
			)
		)
		(property "Value" ""
			(at 0 0 90)
			(layer "F.Fab")
			(effects
				(font
					(size 1.27 1.27)
				)
			)
		)
		(duplicate_pad_numbers_are_jumpers no)
		(fp_line
			(start 0.7874 -0.4064)
			(end 0.7874 0.4064)
			(stroke
				(width 0.1524)
				(type default)
			)
			(layer "F.SilkS")
		)
		(fp_line
			(start -0.7874 -0.4064)
			(end 0.7874 -0.4064)
			(stroke
				(width 0.1524)
				(type default)
			)
			(layer "F.SilkS")
		)
		(fp_line
			(start 0.7874 0.4064)
			(end -0.7874 0.4064)
			(stroke
				(width 0.1524)
				(type default)
			)
			(layer "F.SilkS")
		)
		(fp_line
			(start -0.7874 0.4064)
			(end -0.7874 -0.4064)
			(stroke
				(width 0.1524)
				(type default)
			)
			(layer "F.SilkS")
		)
		(fp_line
			(start -0.12065 -0.305054)
			(end -0.12065 -0.2794)
			(stroke
				(width 0.1)
				(type default)
			)
			(layer "F.Fab")
		)
		(fp_line
			(start -0.67945 -0.305054)
			(end -0.12065 -0.305054)
			(stroke
				(width 0.1)
				(type default)
			)
			(layer "F.Fab")
		)
		(fp_line
			(start 0.67945 -0.3048)
			(end 0.67945 0.3048)
			(stroke
				(width 0.1)
				(type default)
			)
			(layer "F.Fab")
		)
		(fp_line
			(start 0.12065 -0.3048)
			(end 0.67945 -0.3048)
			(stroke
				(width 0.1)
				(type default)
			)
			(layer "F.Fab")
		)
		(fp_line
			(start 0.12065 -0.2794)
			(end 0.12065 -0.3048)
			(stroke
				(width 0.1)
				(type default)
			)
			(layer "F.Fab")
		)
		(fp_line
			(start -0.12065 -0.2794)
			(end 0.12065 -0.2794)
			(stroke
				(width 0.1)
				(type default)
			)
			(layer "F.Fab")
		)
		(fp_line
			(start 0.120396 0.2794)
			(end -0.12065 0.2794)
			(stroke
				(width 0.1)
				(type default)
			)
			(layer "F.Fab")
		)
		(fp_line
			(start -0.12065 0.2794)
			(end -0.12065 0.3048)
			(stroke
				(width 0.1)
				(type default)
			)
			(layer "F.Fab")
		)
		(fp_line
			(start 0.67945 0.3048)
			(end 0.120396 0.3048)
			(stroke
				(width 0.1)
				(type default)
			)
			(layer "F.Fab")
		)
		(fp_line
			(start 0.120396 0.3048)
			(end 0.120396 0.2794)
			(stroke
				(width 0.1)
				(type default)
			)
			(layer "F.Fab")
		)
		(fp_line
			(start -0.12065 0.3048)
			(end -0.67945 0.3048)
			(stroke
				(width 0.1)
				(type default)
			)
			(layer "F.Fab")
		)
		(fp_line
			(start -0.67945 0.3048)
			(end -0.67945 -0.305054)
			(stroke
				(width 0.1)
				(type default)
			)
			(layer "F.Fab")
		)
		(pad "1" smd circle
			(at -0.40005 0 90)
			(size 0 0)
			(layers "F.Cu" "F.Mask" "F.Paste")
			(net "CLK_25M_CK440_ISCLK_REF_DN")
		)
		(pad "2" smd circle
			(at 0.40005 0 90)
			(size 0 0)
			(layers "F.Cu" "F.Mask" "F.Paste")
			(net "CLK_25M_PCH_REF_NS_DN")
		)
	)
	(footprint ""
		(layer "F.Cu")
		(at 428.226474 -125.80366)
		(property "Reference" "PR357"
			(at 0 0 0)
			(layer "F.SilkS")
			(hide yes)
			(effects
				(font
					(size 1.27 1.27)
				)
			)
		)
		(property "Value" ""
			(at 0 0 0)
			(layer "F.Fab")
			(effects
				(font
					(size 1.27 1.27)
				)
			)
		)
		(duplicate_pad_numbers_are_jumpers no)
		(fp_line
			(start -0.7874 -0.4064)
			(end 0.7874 -0.4064)
			(stroke
				(width 0.1524)
				(type default)
			)
			(layer "F.SilkS")
		)
		(fp_line
			(start -0.7874 0.4064)
			(end -0.7874 -0.4064)
			(stroke
				(width 0.1524)
				(type default)
			)
			(layer "F.SilkS")
		)
		(fp_line
			(start 0.7874 -0.4064)
			(end 0.7874 0.4064)
			(stroke
				(width 0.1524)
				(type default)
			)
			(layer "F.SilkS")
		)
		(fp_line
			(start 0.7874 0.4064)
			(end -0.7874 0.4064)
			(stroke
				(width 0.1524)
				(type default)
			)
			(layer "F.SilkS")
		)
		(fp_line
			(start -0.67945 -0.305054)
			(end -0.12065 -0.305054)
			(stroke
				(width 0.1)
				(type default)
			)
			(layer "F.Fab")
		)
		(fp_line
			(start -0.67945 0.3048)
			(end -0.67945 -0.305054)
			(stroke
				(width 0.1)
				(type default)
			)
			(layer "F.Fab")
		)
		(fp_line
			(start -0.12065 -0.305054)
			(end -0.12065 -0.2794)
			(stroke
				(width 0.1)
				(type default)
			)
			(layer "F.Fab")
		)
		(fp_line
			(start -0.12065 -0.2794)
			(end 0.12065 -0.2794)
			(stroke
				(width 0.1)
				(type default)
			)
			(layer "F.Fab")
		)
		(fp_line
			(start -0.12065 0.2794)
			(end -0.12065 0.3048)
			(stroke
				(width 0.1)
				(type default)
			)
			(layer "F.Fab")
		)
		(fp_line
			(start -0.12065 0.3048)
			(end -0.67945 0.3048)
			(stroke
				(width 0.1)
				(type default)
			)
			(layer "F.Fab")
		)
		(fp_line
			(start 0.120396 0.2794)
			(end -0.12065 0.2794)
			(stroke
				(width 0.1)
				(type default)
			)
			(layer "F.Fab")
		)
		(fp_line
			(start 0.120396 0.3048)
			(end 0.120396 0.2794)
			(stroke
				(width 0.1)
				(type default)
			)
			(layer "F.Fab")
		)
		(fp_line
			(start 0.12065 -0.3048)
			(end 0.67945 -0.3048)
			(stroke
				(width 0.1)
				(type default)
			)
			(layer "F.Fab")
		)
		(fp_line
			(start 0.12065 -0.2794)
			(end 0.12065 -0.3048)
			(stroke
				(width 0.1)
				(type default)
			)
			(layer "F.Fab")
		)
		(fp_line
			(start 0.67945 -0.3048)
			(end 0.67945 0.3048)
			(stroke
				(width 0.1)
				(type default)
			)
			(layer "F.Fab")
		)
		(fp_line
			(start 0.67945 0.3048)
			(end 0.120396 0.3048)
			(stroke
				(width 0.1)
				(type default)
			)
			(layer "F.Fab")
		)
		(pad "1" smd circle
			(at -0.40005 0)
			(size 0 0)
			(layers "F.Cu" "F.Mask" "F.Paste")
			(net "PVCCD_HV_CPU0_VREF")
		)
		(pad "2" smd circle
			(at 0.40005 0)
			(size 0 0)
			(layers "F.Cu" "F.Mask" "F.Paste")
			(net "PVCCD_HV_CPU0_ADDR")
		)
	)
)
